FILE_TYPE = CONNECTIVITY;
{Allegro Design Entry HDL 17.2-2016 S081 (4005846) 1/11/2022}
"PAGE_NUMBER" = 171;
0"NC";
1"GND\g";
2"GND\g";
3"GND\g";
4"GND\g";
5"GND\g";
6"GND\g";
7"CLK_100M_PE_M2_0_R_DN"CDS_PHYS_NET_NAME"CLK_100M_GPU_2_R_DN";
8"CLK_100M_E1S_0_DP"CDS_PHYS_NET_NAME"CLK_100M_GPU_1_DP";
9"CLK_100M_E1S_0_DN"CDS_PHYS_NET_NAME"CLK_100M_GPU_1_DN";
10"RTC_EXT_CAP";
11"CLK_100M_E1S_0_R_DP"CDS_PHYS_NET_NAME"CLK_100M_GPU_1_R_DP";
12"CLK_100M_E1S_0_R_DN"CDS_PHYS_NET_NAME"CLK_100M_GPU_1_R_DN";
13"CLK_100M_PE_M2_0_R_DP"CDS_PHYS_NET_NAME"CLK_100M_GPU_2_R_DP";
14"CLK_100M_PE_M2_0_DN"CDS_PHYS_NET_NAME"CLK_100M_GPU_2_DN";
15"CLK_100M_PE_M2_0_DP"CDS_PHYS_NET_NAME"CLK_100M_GPU_2_DP";
16"CLK_25M_PCH_CPU0_DN";
17"TP_CLK_100M_PCH_1_DN";
18"CLK_100M_PE_M2_0_R_DN";
19"CLK_100M_E1S_0_R_DN";
20"TP_CLK_100M_PCH_4_DN";
21"TP_CLK_100M_PCH_1_DP";
22"CLK_25M_PCH_CPU1_DN";
23"CLK_25M_PCH_CPU1_DP";
24"XTAL_PCH_RTC2_R";
25"TP_CLK_100M_PCH_0_DP";
26"CLK_25M_PCH_CPU0_DP";
27"XTAL_PCH_25M_IN";
28"XTAL_PCH_RTC2";
29"XTAL_PCH_25M_IN_R"CDS_PHYS_NET_NAME"XTAL_PCH_25M_IN";
30"XTAL_PCH_25M_OUT";
31"XTAL_PCH_RTC1";
32"CLK_100M_E1S_0_R_DP";
33"CLK_100M_PE_M2_0_R_DP";
34"TP_CLK_100M_PCH_0_DN";
35"TP_CLK_100M_PCH_5_DN";
36"CLK_100M_BMC_P3E_DN";
37"TP_CLK_100M_PCH_4_DP";
38"TP_CLK_100M_PCH_5_DP";
39"CLK_100M_BMC_P3E_DP";
40"TP_CLK_100M_PCH_7_DN";
41"PD_PCH_XCLK_BIASREF";
42"TP_PCH_RSVD<19>";
43"TP_CLK_100M_PCH_7_DP";
44"TP_CLK_100M_PCH_8_DN";
45"TP_CLK_100M_PCH_8_DP";
46"TP_CLK_100M_PCH_9_DN";
47"TP_CLK_100M_PCH_10_DN";
48"TP_CLK_100M_PCH_16_DP";
49"XTAL_PCH_RTC1";
50"CLK_100M_CK440_PCH_EXTCLK_DN";
51"CLK_100M_CK440_PCH_EXTCLK_DP";
52"CLK_25M_PCH_REF_NS_DP";
53"CLK_25M_PCH_REF_NS_DN";
54"TP_PCH_RSVD<18>";
55"TP_CLK_100M_PCH_12_DN";
56"TP_CLK_100M_PCH_13_DN";
57"TP_CLK_100M_PCH_15_DN";
58"TP_CLK_100M_PCH_16_DN";
59"TP_CLK_100M_PCH_13_DP";
60"TP_CLK_100M_PCH_14_DP";
61"XTAL_PCH_25M_OUT";
62"XTAL_PCH_25M_IN";
63"TP_CLK_100M_PCH_14_DN";
64"TP_CLK_100M_PCH_15_DP";
65"XTAL_PCH_RTC2";
66"TP_CLK_100M_PCH_12_DP";
67"TP_CLK_100M_PCH_9_DP";
68"TP_CLK_100M_PCH_10_DP";
69"TP_CLK_100M_PCH_11_DN";
70"TP_CLK_100M_PCH_11_DP";
%"UNIVERSAL_GND"
"1","(-1300,-1025)","0","logical_power","I1";
;
HDL_POWER"GND"
CDS_LIB"logical_power";
"A"6;
%"Q_CAP"
"1","(1125,-775)","0","pure_quanta","I10";
;
PART_NUMBER"CH01806JB07"
VALUE"18PF"
VOLTAGE"50V"
TOLERANCE"5%"
PACK_TYPE"0402"
MATERIAL"C0G"
$LOCATION"C1507"
CDS_LIB"pure_quanta"
CDS_LOCATION"C1507"
$SEC"1"
CDS_SEC"1";
"B"
$PN"2"4;
"A"
$PN"1"24;
%"Q_RES"
"1","(-325,675)","0","pure_quanta","I103";
;
PART_NUMBER"CS00002JB13"
MATERIAL"EMPTY"
WATTAGE"1/16W"
VALUE"0"
PACK_TYPE"0402LF"
TOLERANCE"5%"
$LOCATION"R1720"
CDS_LIB"pure_quanta"
CDS_LOCATION"R1720"
$SEC"1"
CDS_SEC"1";
"B"
$PN"2"27;
"A"
$PN"1"29;
%"Q_RES"
"1","(2200,225)","0","pure_quanta","I104";
;
PART_NUMBER"CS00002JB13"
PACK_TYPE"0402LF"
WATTAGE"1/16W"
MATERIAL"CHIP"
TOLERANCE"5%"
VALUE"0"
$LOCATION"R1721"
CDS_LIB"pure_quanta"
CDS_LOCATION"R1721"
$SEC"1"
CDS_SEC"1";
"B"
$PN"2"28;
"A"
$PN"1"24;
%"Q_CRYSTAL"
"1","(1700,-475)","0","pure_quanta","I11";
;
PART_NUMBER"BG632768012"
VALUE"32.768KHZ"
MATERIAL"IC"
PACK_TYPE"SMLF"
$LOCATION"Y1"
SEC_TYPE"SMLF"
NEEDS_NO_SIZE"TRUE"
CDS_LIB"pure_quanta"
CDS_LOCATION"Y1"
SEC"1";
"2"
$PN"2"31;
"1"
$PN"1"24;
%"Q_RES"
"1","(1350,1300)","0","pure_quanta","I116";
;
PART_NUMBER"CS00002JB13"
MATERIAL"CHIP"
WATTAGE"1/16W"
TOLERANCE"5%"
VALUE"0"
PACK_TYPE"0402LF"
$LOCATION"R4305"
CDS_LIB"pure_quanta"
CDS_LOCATION"R4305"
$SEC"1"
CDS_SEC"1";
"B"
$PN"2"15;
"A"
$PN"1"13;
%"Q_RES"
"1","(1350,1150)","0","pure_quanta","I117";
;
PART_NUMBER"CS00002JB13"
VALUE"0"
MATERIAL"CHIP"
WATTAGE"1/16W"
TOLERANCE"5%"
PACK_TYPE"0402LF"
$LOCATION"R4306"
CDS_LIB"pure_quanta"
CDS_LOCATION"R4306"
$SEC"1"
CDS_SEC"1";
"B"
$PN"2"14;
"A"
$PN"1"7;
%"Q_RES"
"1","(1350,1675)","0","pure_quanta","I121";
;
PART_NUMBER"CS02202FB02"
VALUE"22"
MATERIAL"CHIP"
LOCATION"R4303"
CDS_LIB"pure_quanta"
WATTAGE"1/16W"
TOLERANCE"1%"
PACK_TYPE"0402LF"
$SEC"1"
CDS_SEC"1";
"B"
$PN"2"8;
"A"
$PN"1"11;
%"Q_RES"
"1","(1350,1525)","0","pure_quanta","I122";
;
PART_NUMBER"CS02202FB02"
VALUE"22"
MATERIAL"CHIP"
LOCATION"R4304"
PACK_TYPE"0402LF"
TOLERANCE"1%"
WATTAGE"1/16W"
CDS_LIB"pure_quanta"
$SEC"1"
CDS_SEC"1";
"B"
$PN"2"9;
"A"
$PN"1"12;
%"UNIVERSAL_GND"
"1","(2275,-1025)","0","logical_power","I16";
;
HDL_POWER"GND"
CDS_LIB"logical_power";
"A"3;
%"Q_CAP"
"1","(2275,-775)","0","pure_quanta","I17";
;
PART_NUMBER"CH01806JB07"
PACK_TYPE"0402"
VALUE"18PF"
VOLTAGE"50V"
MATERIAL"C0G"
TOLERANCE"5%"
$LOCATION"C1508"
CDS_LIB"pure_quanta"
CDS_LOCATION"C1508"
$SEC"1"
CDS_SEC"1";
"B"
$PN"2"3;
"A"
$PN"1"31;
%"UNIVERSAL_GND"
"1","(-1775,3600)","0","logical_power","I5";
;
HDL_POWER"GND"
CDS_LIB"logical_power";
"A"2;
%"Q_RES"
"2","(-1775,3850)","0","pure_quanta","I69";
;
PART_NUMBER"CS06042FB03"
VALUE"60.4"
WATTAGE"1/16W"
MATERIAL"CHIP"
PACK_TYPE"0402LF"
TOLERANCE"1%"
$LOCATION"R477"
CDS_LIB"pure_quanta"
CDS_LOCATION"R477"
$SEC"1"
CDS_SEC"1";
"A"
$PN"1"41;
"B"
$PN"2"2;
%"UNIVERSAL_GND"
"1","(-375,-1025)","0","logical_power","I7";
;
HDL_POWER"GND"
CDS_LIB"logical_power";
"A"5;
%"Q_RES"
"1","(1675,-100)","0","pure_quanta","I74";
;
PART_NUMBER"CS61003F901"
MATERIAL"CHIP"
TOLERANCE"1%"
PACK_TYPE"0603LF"
VALUE"10M"
WATTAGE"1/10W"
$LOCATION"R120"
CDS_LIB"pure_quanta"
CDS_LOCATION"R120"
$SEC"1"
CDS_SEC"1";
"B"
$PN"2"31;
"A"
$PN"1"24;
%"Q_XTAL_4P_13BI_24GND"
"1","(-825,-450)","0","pure_quanta","I75";
;
PART_NUMBER"BG625000802"
MATERIAL"EMPTY"
PART_TYPE"SMLF"
VALUE"25MHZ"
$LOCATION"Y7"
CDS_LIB"pure_quanta"
CDS_LMAN_SYM_OUTLINE"-125,175,125,-175"
PIN_NAMES_ROTATE"True"
CDS_LOCATION"Y7"
$SEC"1"
CDS_SEC"1";
"X2"
$PN"3"30;
"G2"
$PN"4"5;
"G1"
$PN"2"6;
"X1"
$PN"1"29;
%"Q_CAP"
"1","(-375,-775)","0","pure_quanta","I76";
;
PART_NUMBER"CH02706JB06"
MATERIAL"EMPTY"
VALUE"27PF  "
VOLTAGE"50V "
TOLERANCE"5% "
PACK_TYPE"0402"
$LOCATION"C104"
CDS_LIB"pure_quanta"
CDS_LOCATION"C104"
$SEC"1"
CDS_SEC"1";
"B"
$PN"2"5;
"A"
$PN"1"30;
%"Q_CAP"
"1","(-1300,-775)","2","pure_quanta","I77";
;
PART_NUMBER"CH02706JB06"
MATERIAL"EMPTY"
TOLERANCE"5% "
VOLTAGE"50V "
VALUE"27PF  "
PACK_TYPE"0402"
$LOCATION"C103"
CDS_LIB"pure_quanta"
CDS_LOCATION"C103"
$SEC"1"
CDS_SEC"1";
"B"
$PN"2"6;
"A"
$PN"1"29;
%"EMMITSBURG_REV0P9"
"1","(1525,3175)","0","pure_quanta","I78";
;
PART_NUMBER"AJ0QV2N0T00"
VALUE"GFNOCPU04302300-QV2N-MM#99A1WT"
MATERIAL"IC"
PART_TYPE"SMLF"
$LOCATION"U4"
NEEDS_NO_SIZE"TRUE"
CDS_LMAN_SYM_OUTLINE"-850,1125,850,-1125"
CDS_LIB"pure_quanta"
CDS_LOCATION"U4"
$SEC"1"
CDS_SEC"1";
"XTAL_OUT"
$PN"D23"61;
"XTAL_IN"
$PN"B23"62;
"RTC_EXTCAP"
$PN"BF5"10;
"RTCX2"
$PN"BF7"65;
"RTCX1"
$PN"BE6"49;
"REFCLK_INJ_S_P"
$PN"B21"51;
"REFCLK_INJ_S_N \B"
$PN"D21"50;
"REFCLK_INJ_NS_P"
$PN"B25"52;
"REFCLK_INJ_NS_N \B"
$PN"D25"53;
"PMSYNC_CLK_P_1"
$PN"A28"23;
"PMSYNC_CLK_P_0"
$PN"B27"26;
"PMSYNC_CLK_N_1"
$PN"C28"22;
"PMSYNC_CLK_N_0"
$PN"D27"16;
"CLKOUT_SRC_P_9"
$PN"D15"67;
"CLKOUT_SRC_P_8"
$PN"H18"45;
"CLKOUT_SRC_P_7"
$PN"C14"43;
"CLKOUT_SRC_P_6"
$PN"D11"39;
"CLKOUT_SRC_P_5"
$PN"C12"38;
"CLKOUT_SRC_P_4"
$PN"D19"37;
"CLKOUT_SRC_P_3"
$PN"D17"32;
"CLKOUT_SRC_P_2"
$PN"K21"33;
"CLKOUT_SRC_P_16"
$PN"C18"48;
"CLKOUT_SRC_P_15"
$PN"C6"64;
"CLKOUT_SRC_P_14"
$PN"D7"60;
"CLKOUT_SRC_P_13"
$PN"C8"59;
"CLKOUT_SRC_P_12"
$PN"C10"66;
"CLKOUT_SRC_P_11"
$PN"H15"70;
"CLKOUT_SRC_P_10"
$PN"K18"68;
"CLKOUT_SRC_P_1"
$PN"F21"21;
"CLKOUT_SRC_P_0"
$PN"C16"25;
"CLKOUT_SRC_N_9"
$PN"B15"46;
"CLKOUT_SRC_N_8"
$PN"F18"44;
"CLKOUT_SRC_N_7"
$PN"A14"40;
"CLKOUT_SRC_N_6"
$PN"B11"36;
"CLKOUT_SRC_N_5"
$PN"A12"35;
"CLKOUT_SRC_N_4"
$PN"B19"20;
"CLKOUT_SRC_N_3"
$PN"B17"19;
"CLKOUT_SRC_N_2"
$PN"H21"18;
"CLKOUT_SRC_N_16"
$PN"A18"58;
"CLKOUT_SRC_N_15"
$PN"B5"57;
"CLKOUT_SRC_N_14"
$PN"B7"63;
"CLKOUT_SRC_N_13"
$PN"A8"56;
"CLKOUT_SRC_N_12"
$PN"A10"55;
"CLKOUT_SRC_N_11"
$PN"G16"69;
"CLKOUT_SRC_N_10"
$PN"J16"47;
"CLKOUT_SRC_N_1"
$PN"G23"17;
"CLKOUT_SRC_N_0"
$PN"A16"34;
"XCLK_BIASREF"
$PN"N29"41;
"RSVD_H24"
$PN"H24"54;
"RSVD_J23"
$PN"J23"42;
%"Q_CAP"
"1","(-800,2950)","2","pure_quanta","I89";
;
PART_NUMBER"CH4104K1B00"
VALUE"0.1UF"
PACK_TYPE"0402"
TOLERANCE"10%"
MATERIAL"X7R"
VOLTAGE"25V"
$LOCATION"C609"
CDS_LIB"pure_quanta"
CDS_LOCATION"C609"
$SEC"1"
CDS_SEC"1";
"B"
$PN"2"1;
"A"
$PN"1"10;
%"UNIVERSAL_GND"
"1","(1125,-1025)","0","logical_power","I9";
;
HDL_POWER"GND"
CDS_LIB"logical_power";
"A"4;
%"UNIVERSAL_GND"
"1","(-800,2700)","0","logical_power","I90";
;
CDS_LIB"logical_power"
HDL_POWER"GND";
"A"1;
%"Q_RES"
"1","(-875,275)","0","pure_quanta","I92";
;
PART_NUMBER"CS42003B902"
MATERIAL"EMPTY"
VALUE"200K"
WATTAGE"1/10W"
PACK_TYPE"0603LF"
TOLERANCE"0.1%"
$LOCATION"R1316"
CDS_LIB"pure_quanta"
CDS_LOCATION"R1316"
$SEC"1"
CDS_SEC"1";
"B"
$PN"2"30;
"A"
$PN"1"29;
END.
